# T6G (Grand Teton) — schematic netlist excerpt (pin names and nets, part order shuffled) for the footprints in the layout excerpt that follows; sources: Cadence DE-HDL packaged netlist, KiCad conversion of 04192023_DAF0TMB3IC0_F0TG_MB_C_brd_V02_OCP.brd

C850  Q_CAP_DIFFBUS  DIFF BUS_0.22UF 6.3V 20% X6S  pkg C0201  page 64 : \1\ = P5E_CPU0_P2_TX_C_DN<9> ; \2\ = P5E_CPU0_P2_TX_DN<9>

(kicad_pcb
	(version 20260206)
	(generator "pcbnew")
	(generator_version "10.0")
	(general
		(thickness 1.6)
		(legacy_teardrops no)
	)
	(paper "A4")
	(title_block
		(title "04192023_DAF0TMB3IC0_F0TG_MB_C_brd_V02_OCP.brd")
		(comment 1 "Grand Teton / footprints 3101-3101 of 8354")
	)
	(layers
		(0 "F.Cu" signal "TOP")
		(4 "In1.Cu" signal "GND")
		(6 "In2.Cu" signal "IN1")
		(8 "In3.Cu" signal "GND1")
		(10 "In4.Cu" signal "IN2")
		(12 "In5.Cu" signal "GND2")
		(14 "In6.Cu" signal "IN3")
		(16 "In7.Cu" signal "GND3")
		(18 "In8.Cu" signal "VCC")
		(20 "In9.Cu" signal "VCC1")
		(22 "In10.Cu" signal "GND4")
		(24 "In11.Cu" signal "IN4")
		(26 "In12.Cu" signal "GND5")
		(28 "In13.Cu" signal "IN5")
		(30 "In14.Cu" signal "GND6")
		(32 "In15.Cu" signal "IN6")
		(34 "In16.Cu" signal "GND7")
		(2 "B.Cu" signal "BOTTOM")
		(9 "F.Adhes" user "F.Adhesive")
		(11 "B.Adhes" user "B.Adhesive")
		(13 "F.Paste" user "Package Geometry/Pastemask Top")
		(15 "B.Paste" user "Package Geometry/Pastemask Bottom")
		(5 "F.SilkS" user "Ref Des/Silkscreen Top")
		(7 "B.SilkS" user "Ref Des/Silkscreen Bottom")
		(1 "F.Mask" user "Board Geometry/Soldermask Top")
		(3 "B.Mask" user "Board Geometry/Soldermask Bottom")
		(17 "Dwgs.User" user "User.Drawings")
		(19 "Cmts.User" user "User.Comments")
		(21 "Eco1.User" user "User.Eco1")
		(23 "Eco2.User" user "User.Eco2")
		(25 "Edge.Cuts" user "Board Geometry/Outline")
		(27 "Margin" user)
		(31 "F.CrtYd" user "Package Geometry/Place Bound Top")
		(29 "B.CrtYd" user "Package Geometry/Place Bound Bottom")
		(35 "F.Fab" user "Ref Des/Assembly Top")
		(33 "B.Fab" user "Ref Des/Assembly Bottom")
	)
	(footprint ""
		(layer "F.Cu")
		(at 414.84804 -378.95403 -90)
		(property "Reference" "C850"
			(at 0 0 270)
			(layer "F.SilkS")
			(hide yes)
			(effects
				(font
					(size 1.27 1.27)
				)
			)
		)
		(property "Value" ""
			(at 0 0 270)
			(layer "F.Fab")
			(effects
				(font
					(size 1.27 1.27)
				)
			)
		)
		(duplicate_pad_numbers_are_jumpers no)
		(fp_line
			(start -0.299974 0.150114)
			(end -0.299974 -0.150114)
			(stroke
				(width 0.1)
				(type default)
			)
			(layer "F.Fab")
		)
		(fp_line
			(start 0.299974 0.150114)
			(end -0.299974 0.150114)
			(stroke
				(width 0.1)
				(type default)
			)
			(layer "F.Fab")
		)
		(fp_line
			(start -0.299974 -0.150114)
			(end 0.299974 -0.150114)
			(stroke
				(width 0.1)
				(type default)
			)
			(layer "F.Fab")
		)
		(fp_line
			(start 0.299974 -0.150114)
			(end 0.299974 0.150114)
			(stroke
				(width 0.1)
				(type default)
			)
			(layer "F.Fab")
		)
		(pad "1" smd rect
			(at -0.2667 0 270)
			(size 0.3048 0.381)
			(layers "F.Cu" "F.Mask" "F.Paste")
			(net "P5E_CPU0_P2_TX_C_DN<9>")
		)
		(pad "2" smd rect
			(at 0.2667 0 270)
			(size 0.3048 0.381)
			(layers "F.Cu" "F.Mask" "F.Paste")
			(net "P5E_CPU0_P2_TX_DN<9>")
		)
	)
)
